# T6G (Grand Teton) — schematic netlist excerpt (pin names and nets, part order shuffled) for the footprints in the layout excerpt that follows; sources: Cadence DE-HDL packaged netlist, KiCad conversion of 04192023_DAF0TMB3IC0_F0TG_MB_C_brd_V02_OCP.brd

PC106  Q_CAPP  220UF 4V 20% SPCAP  pkg SMLF  page 218 : A = PVDDCR_CPU1_P1 ; B = GND
PC221_2  Q_CAP  22UF 4V 20% X6S  pkg C0805  page 208 : A = PVDD11_S3_P0 ; B = GND
C2613  Q_CAP  22UF 4V 20% X6S  pkg C0402  page 70 : A = PVDDIO_P0 ; B = GND

(kicad_pcb
	(version 20260206)
	(generator "pcbnew")
	(generator_version "10.0")
	(general
		(thickness 1.6)
		(legacy_teardrops no)
	)
	(paper "A4")
	(title_block
		(title "04192023_DAF0TMB3IC0_F0TG_MB_C_brd_V02_OCP.brd")
		(comment 1 "Grand Teton / footprints 6274-6276 of 8354")
	)
	(layers
		(0 "F.Cu" signal "TOP")
		(4 "In1.Cu" signal "GND")
		(6 "In2.Cu" signal "IN1")
		(8 "In3.Cu" signal "GND1")
		(10 "In4.Cu" signal "IN2")
		(12 "In5.Cu" signal "GND2")
		(14 "In6.Cu" signal "IN3")
		(16 "In7.Cu" signal "GND3")
		(18 "In8.Cu" signal "VCC")
		(20 "In9.Cu" signal "VCC1")
		(22 "In10.Cu" signal "GND4")
		(24 "In11.Cu" signal "IN4")
		(26 "In12.Cu" signal "GND5")
		(28 "In13.Cu" signal "IN5")
		(30 "In14.Cu" signal "GND6")
		(32 "In15.Cu" signal "IN6")
		(34 "In16.Cu" signal "GND7")
		(2 "B.Cu" signal "BOTTOM")
		(9 "F.Adhes" user "F.Adhesive")
		(11 "B.Adhes" user "B.Adhesive")
		(13 "F.Paste" user "Package Geometry/Pastemask Top")
		(15 "B.Paste" user "Package Geometry/Pastemask Bottom")
		(5 "F.SilkS" user "Ref Des/Silkscreen Top")
		(7 "B.SilkS" user "Ref Des/Silkscreen Bottom")
		(1 "F.Mask" user "Board Geometry/Soldermask Top")
		(3 "B.Mask" user "Board Geometry/Soldermask Bottom")
		(17 "Dwgs.User" user "User.Drawings")
		(19 "Cmts.User" user "User.Comments")
		(21 "Eco1.User" user "User.Eco1")
		(23 "Eco2.User" user "User.Eco2")
		(25 "Edge.Cuts" user "Board Geometry/Outline")
		(27 "Margin" user)
		(31 "F.CrtYd" user "Package Geometry/Place Bound Top")
		(29 "B.CrtYd" user "Package Geometry/Place Bound Bottom")
		(35 "F.Fab" user "Ref Des/Assembly Top")
		(33 "B.Fab" user "Ref Des/Assembly Bottom")
	)
	(footprint ""
		(layer "B.Cu")
		(at 420.160958 -342.007952 -90)
		(property "Reference" "PC221_2"
			(at 0 0 90)
			(layer "B.SilkS")
			(hide yes)
			(effects
				(font
					(size 1.27 1.27)
				)
				(justify mirror)
			)
		)
		(property "Value" ""
			(at 0 0 90)
			(layer "B.Fab")
			(effects
				(font
					(size 1.27 1.27)
				)
				(justify mirror)
			)
		)
		(duplicate_pad_numbers_are_jumpers no)
		(fp_line
			(start -1.524 0.762)
			(end 1.524 0.762)
			(stroke
				(width 0.1524)
				(type default)
			)
			(layer "B.SilkS")
		)
		(fp_line
			(start 1.524 0.762)
			(end 1.524 -0.762)
			(stroke
				(width 0.1524)
				(type default)
			)
			(layer "B.SilkS")
		)
		(fp_line
			(start -1.524 -0.762)
			(end -1.524 0.762)
			(stroke
				(width 0.1524)
				(type default)
			)
			(layer "B.SilkS")
		)
		(fp_line
			(start 1.524 -0.762)
			(end -1.524 -0.762)
			(stroke
				(width 0.1524)
				(type default)
			)
			(layer "B.SilkS")
		)
		(fp_line
			(start -1.1049 0.724916)
			(end -1.1049 -0.724916)
			(stroke
				(width 0.1)
				(type default)
			)
			(layer "B.Fab")
		)
		(fp_line
			(start 1.1049 0.724916)
			(end -1.1049 0.724916)
			(stroke
				(width 0.1)
				(type default)
			)
			(layer "B.Fab")
		)
		(fp_line
			(start -1.1049 -0.724916)
			(end 1.1049 -0.724916)
			(stroke
				(width 0.1)
				(type default)
			)
			(layer "B.Fab")
		)
		(fp_line
			(start 1.1049 -0.724916)
			(end 1.1049 0.724916)
			(stroke
				(width 0.1)
				(type default)
			)
			(layer "B.Fab")
		)
		(pad "1" smd rect
			(at 0.889 0 270)
			(size 1.016 1.27)
			(layers "B.Cu" "B.Mask" "B.Paste")
			(net "PVDD11_S3_P0")
		)
		(pad "2" smd rect
			(at -0.889 0 270)
			(size 1.016 1.27)
			(layers "B.Cu" "B.Mask" "B.Paste")
			(net "GND")
		)
	)
	(footprint ""
		(layer "B.Cu")
		(at 353.900232 -260.305042 180)
		(property "Reference" "C2613"
			(at 0 0 0)
			(layer "B.SilkS")
			(hide yes)
			(effects
				(font
					(size 1.27 1.27)
				)
				(justify mirror)
			)
		)
		(property "Value" ""
			(at 0 0 0)
			(layer "B.Fab")
			(effects
				(font
					(size 1.27 1.27)
				)
				(justify mirror)
			)
		)
		(duplicate_pad_numbers_are_jumpers no)
		(fp_line
			(start 0.7874 0.4064)
			(end 0.7874 -0.4064)
			(stroke
				(width 0.1524)
				(type default)
			)
			(layer "B.SilkS")
		)
		(fp_line
			(start 0.7874 -0.4064)
			(end -0.7874 -0.4064)
			(stroke
				(width 0.1524)
				(type default)
			)
			(layer "B.SilkS")
		)
		(fp_line
			(start -0.7874 0.4064)
			(end 0.7874 0.4064)
			(stroke
				(width 0.1524)
				(type default)
			)
			(layer "B.SilkS")
		)
		(fp_line
			(start -0.7874 -0.4064)
			(end -0.7874 0.4064)
			(stroke
				(width 0.1524)
				(type default)
			)
			(layer "B.SilkS")
		)
		(fp_line
			(start 0.67945 0.3048)
			(end 0.67945 -0.305054)
			(stroke
				(width 0.1)
				(type default)
			)
			(layer "B.Fab")
		)
		(fp_line
			(start 0.67945 -0.305054)
			(end 0.12065 -0.305054)
			(stroke
				(width 0.1)
				(type default)
			)
			(layer "B.Fab")
		)
		(fp_line
			(start 0.12065 0.3048)
			(end 0.67945 0.3048)
			(stroke
				(width 0.1)
				(type default)
			)
			(layer "B.Fab")
		)
		(fp_line
			(start 0.12065 0.2794)
			(end 0.12065 0.3048)
			(stroke
				(width 0.1)
				(type default)
			)
			(layer "B.Fab")
		)
		(fp_line
			(start 0.12065 -0.2794)
			(end -0.12065 -0.2794)
			(stroke
				(width 0.1)
				(type default)
			)
			(layer "B.Fab")
		)
		(fp_line
			(start 0.12065 -0.305054)
			(end 0.12065 -0.2794)
			(stroke
				(width 0.1)
				(type default)
			)
			(layer "B.Fab")
		)
		(fp_line
			(start -0.120396 0.3048)
			(end -0.120396 0.2794)
			(stroke
				(width 0.1)
				(type default)
			)
			(layer "B.Fab")
		)
		(fp_line
			(start -0.120396 0.2794)
			(end 0.12065 0.2794)
			(stroke
				(width 0.1)
				(type default)
			)
			(layer "B.Fab")
		)
		(fp_line
			(start -0.12065 -0.2794)
			(end -0.12065 -0.3048)
			(stroke
				(width 0.1)
				(type default)
			)
			(layer "B.Fab")
		)
		(fp_line
			(start -0.12065 -0.3048)
			(end -0.67945 -0.3048)
			(stroke
				(width 0.1)
				(type default)
			)
			(layer "B.Fab")
		)
		(fp_line
			(start -0.67945 0.3048)
			(end -0.120396 0.3048)
			(stroke
				(width 0.1)
				(type default)
			)
			(layer "B.Fab")
		)
		(fp_line
			(start -0.67945 -0.3048)
			(end -0.67945 0.3048)
			(stroke
				(width 0.1)
				(type default)
			)
			(layer "B.Fab")
		)
		(pad "1" smd circle
			(at 0.40005 0)
			(size 0 0)
			(layers "B.Cu" "B.Mask" "B.Paste")
			(net "PVDDIO_P0")
		)
		(pad "2" smd circle
			(at -0.40005 0)
			(size 0 0)
			(layers "B.Cu" "B.Mask" "B.Paste")
			(net "GND")
		)
	)
	(footprint ""
		(layer "B.Cu")
		(at 104.307894 -333.125826 -90)
		(property "Reference" "PC106"
			(at 7.440676 -3.261106 270)
			(unlocked yes)
			(layer "B.SilkS")
			(effects
				(font
					(size 0.7874 0.5842)
					(thickness 0.1524)
				)
				(justify left mirror)
			)
		)
		(property "Value" ""
			(at 0 0 90)
			(layer "B.Fab")
			(effects
				(font
					(size 1.27 1.27)
				)
				(justify mirror)
			)
		)
		(duplicate_pad_numbers_are_jumpers no)
		(fp_line
			(start -4.533392 2.249932)
			(end 4.533392 2.249932)
			(stroke
				(width 0.1524)
				(type default)
			)
			(layer "B.SilkS")
		)
		(fp_line
			(start 4.533392 2.249932)
			(end 4.533392 -2.249932)
			(stroke
				(width 0.1524)
				(type default)
			)
			(layer "B.SilkS")
		)
		(fp_line
			(start -4.533392 -2.249932)
			(end -4.533392 2.249932)
			(stroke
				(width 0.1524)
				(type default)
			)
			(layer "B.SilkS")
		)
		(fp_line
			(start 4.533392 -2.249932)
			(end -4.533392 -2.249932)
			(stroke
				(width 0.1524)
				(type default)
			)
			(layer "B.SilkS")
		)
		(fp_rect
			(start 5.39242 2.326132)
			(end 4.533392 -2.326132)
			(stroke
				(width 0)
				(type default)
			)
			(fill yes)
			(layer "B.SilkS")
		)
		(fp_line
			(start -3.750056 2.249932)
			(end 3.750056 2.249932)
			(stroke
				(width 0.1)
				(type default)
			)
			(layer "B.Fab")
		)
		(fp_line
			(start 3.750056 2.249932)
			(end 3.750056 -2.249932)
			(stroke
				(width 0.1)
				(type default)
			)
			(layer "B.Fab")
		)
		(fp_line
			(start -3.750056 -2.249932)
			(end -3.750056 2.249932)
			(stroke
				(width 0.1)
				(type default)
			)
			(layer "B.Fab")
		)
		(fp_line
			(start 3.750056 -2.249932)
			(end -3.750056 -2.249932)
			(stroke
				(width 0.1)
				(type default)
			)
			(layer "B.Fab")
		)
		(fp_text user "-"
			(at -4.65201 2.95656 270)
			(unlocked yes)
			(layer "B.SilkS")
			(effects
				(font
					(size 1.905 1.4224)
					(thickness 0.1524)
				)
				(justify left mirror)
			)
		)
		(fp_text user "+"
			(at 6.322314 0.786384 180)
			(unlocked yes)
			(layer "B.SilkS")
			(effects
				(font
					(size 1.905 1.4224)
					(thickness 0.1524)
				)
				(justify left mirror)
			)
		)
		(fp_text user "+"
			(at 6.322314 0.786384 180)
			(unlocked yes)
			(layer "B.Fab")
			(effects
				(font
					(size 1.905 1.4224)
					(thickness 0.1524)
				)
				(justify left mirror)
			)
		)
		(fp_text user "-"
			(at -4.8514 -0.14605 270)
			(unlocked yes)
			(layer "B.Fab")
			(effects
				(font
					(size 1.905 1.4224)
					(thickness 0.1524)
				)
				(justify left mirror)
			)
		)
		(pad "1" smd rect
			(at 3.199892 0 90)
			(size 2.413 2.8194)
			(layers "B.Cu" "B.Mask" "B.Paste")
			(net "PVDDCR_CPU1_P1")
		)
		(pad "2" smd rect
			(at -3.199892 0 90)
			(size 2.413 2.8194)
			(layers "B.Cu" "B.Mask" "B.Paste")
			(net "GND")
		)
	)
)
